# T6G (Grand Teton) — schematic netlist excerpt (pin names and nets, part order shuffled) for the footprints in the layout excerpt that follows; sources: Cadence DE-HDL packaged netlist, KiCad conversion of 04192023_DAF0TMB3IC0_F0TG_MB_C_brd_V02_OCP.brd

PR4000  Q_RES  160K 1% CHIP  pkg 0402LF  page 152 : A = P12V_AUX ; B = P12V_SCM_UV
PR85  Q_RES  8.87K 1% EMPTY  pkg 0402LF  page 202 : A = PVDDCR_CPU1_P0_LSET4 ; B = GND
H38  HOLE  EMPTY  pkg TH  page 230 : \1\ = GND
R1081  Q_RES  1K 1% EMPTY  pkg 0201LF  page 299 : A = P1V8_CPU0_RT_1D ; B = RT_CPU0_P2_VQPS

(kicad_pcb
	(version 20260206)
	(generator "pcbnew")
	(generator_version "10.0")
	(general
		(thickness 1.6)
		(legacy_teardrops no)
	)
	(paper "A4")
	(title_block
		(title "04192023_DAF0TMB3IC0_F0TG_MB_C_brd_V02_OCP.brd")
		(comment 1 "Grand Teton / footprints 684-687 of 8354")
	)
	(layers
		(0 "F.Cu" signal "TOP")
		(4 "In1.Cu" signal "GND")
		(6 "In2.Cu" signal "IN1")
		(8 "In3.Cu" signal "GND1")
		(10 "In4.Cu" signal "IN2")
		(12 "In5.Cu" signal "GND2")
		(14 "In6.Cu" signal "IN3")
		(16 "In7.Cu" signal "GND3")
		(18 "In8.Cu" signal "VCC")
		(20 "In9.Cu" signal "VCC1")
		(22 "In10.Cu" signal "GND4")
		(24 "In11.Cu" signal "IN4")
		(26 "In12.Cu" signal "GND5")
		(28 "In13.Cu" signal "IN5")
		(30 "In14.Cu" signal "GND6")
		(32 "In15.Cu" signal "IN6")
		(34 "In16.Cu" signal "GND7")
		(2 "B.Cu" signal "BOTTOM")
		(9 "F.Adhes" user "F.Adhesive")
		(11 "B.Adhes" user "B.Adhesive")
		(13 "F.Paste" user "Package Geometry/Pastemask Top")
		(15 "B.Paste" user "Package Geometry/Pastemask Bottom")
		(5 "F.SilkS" user "Ref Des/Silkscreen Top")
		(7 "B.SilkS" user "Ref Des/Silkscreen Bottom")
		(1 "F.Mask" user "Board Geometry/Soldermask Top")
		(3 "B.Mask" user "Board Geometry/Soldermask Bottom")
		(17 "Dwgs.User" user "User.Drawings")
		(19 "Cmts.User" user "User.Comments")
		(21 "Eco1.User" user "User.Eco1")
		(23 "Eco2.User" user "User.Eco2")
		(25 "Edge.Cuts" user "Board Geometry/Outline")
		(27 "Margin" user)
		(31 "F.CrtYd" user "Package Geometry/Place Bound Top")
		(29 "B.CrtYd" user "Package Geometry/Place Bound Bottom")
		(35 "F.Fab" user "Ref Des/Assembly Top")
		(33 "B.Fab" user "Ref Des/Assembly Bottom")
	)
	(footprint ""
		(layer "F.Cu")
		(at 307.391562 -351.927922)
		(property "Reference" "PR85"
			(at 0 0 0)
			(layer "F.SilkS")
			(hide yes)
			(effects
				(font
					(size 1.27 1.27)
				)
			)
		)
		(property "Value" ""
			(at 0 0 0)
			(layer "F.Fab")
			(effects
				(font
					(size 1.27 1.27)
				)
			)
		)
		(duplicate_pad_numbers_are_jumpers no)
		(fp_line
			(start -0.7874 -0.4064)
			(end 0.7874 -0.4064)
			(stroke
				(width 0.1524)
				(type default)
			)
			(layer "F.SilkS")
		)
		(fp_line
			(start -0.7874 0.4064)
			(end -0.7874 -0.4064)
			(stroke
				(width 0.1524)
				(type default)
			)
			(layer "F.SilkS")
		)
		(fp_line
			(start 0.7874 -0.4064)
			(end 0.7874 0.4064)
			(stroke
				(width 0.1524)
				(type default)
			)
			(layer "F.SilkS")
		)
		(fp_line
			(start 0.7874 0.4064)
			(end -0.7874 0.4064)
			(stroke
				(width 0.1524)
				(type default)
			)
			(layer "F.SilkS")
		)
		(fp_line
			(start -0.67945 -0.305054)
			(end -0.12065 -0.305054)
			(stroke
				(width 0.1)
				(type default)
			)
			(layer "F.Fab")
		)
		(fp_line
			(start -0.67945 0.3048)
			(end -0.67945 -0.305054)
			(stroke
				(width 0.1)
				(type default)
			)
			(layer "F.Fab")
		)
		(fp_line
			(start -0.12065 -0.305054)
			(end -0.12065 -0.2794)
			(stroke
				(width 0.1)
				(type default)
			)
			(layer "F.Fab")
		)
		(fp_line
			(start -0.12065 -0.2794)
			(end 0.12065 -0.2794)
			(stroke
				(width 0.1)
				(type default)
			)
			(layer "F.Fab")
		)
		(fp_line
			(start -0.12065 0.2794)
			(end -0.12065 0.3048)
			(stroke
				(width 0.1)
				(type default)
			)
			(layer "F.Fab")
		)
		(fp_line
			(start -0.12065 0.3048)
			(end -0.67945 0.3048)
			(stroke
				(width 0.1)
				(type default)
			)
			(layer "F.Fab")
		)
		(fp_line
			(start 0.120396 0.2794)
			(end -0.12065 0.2794)
			(stroke
				(width 0.1)
				(type default)
			)
			(layer "F.Fab")
		)
		(fp_line
			(start 0.120396 0.3048)
			(end 0.120396 0.2794)
			(stroke
				(width 0.1)
				(type default)
			)
			(layer "F.Fab")
		)
		(fp_line
			(start 0.12065 -0.3048)
			(end 0.67945 -0.3048)
			(stroke
				(width 0.1)
				(type default)
			)
			(layer "F.Fab")
		)
		(fp_line
			(start 0.12065 -0.2794)
			(end 0.12065 -0.3048)
			(stroke
				(width 0.1)
				(type default)
			)
			(layer "F.Fab")
		)
		(fp_line
			(start 0.67945 -0.3048)
			(end 0.67945 0.3048)
			(stroke
				(width 0.1)
				(type default)
			)
			(layer "F.Fab")
		)
		(fp_line
			(start 0.67945 0.3048)
			(end 0.120396 0.3048)
			(stroke
				(width 0.1)
				(type default)
			)
			(layer "F.Fab")
		)
		(pad "1" smd circle
			(at -0.40005 0)
			(size 0 0)
			(layers "F.Cu" "F.Mask" "F.Paste")
			(net "PVDDCR_CPU1_P0_LSET4")
		)
		(pad "2" smd circle
			(at 0.40005 0)
			(size 0 0)
			(layers "F.Cu" "F.Mask" "F.Paste")
			(net "GND")
		)
	)
	(footprint ""
		(layer "F.Cu")
		(at 389.522208 -173.314868)
		(property "Reference" "H38"
			(at -5.712206 2.34696 0)
			(unlocked yes)
			(layer "F.SilkS")
			(effects
				(font
					(size 0.7874 0.5842)
					(thickness 0.1524)
				)
				(justify left)
			)
		)
		(property "Value" ""
			(at 0 0 0)
			(layer "F.Fab")
			(effects
				(font
					(size 1.27 1.27)
				)
			)
		)
		(duplicate_pad_numbers_are_jumpers no)
		(pad "1" thru_hole circle
			(at 0 0)
			(size 6.1976 6.1976)
			(drill 3.7338)
			(layers "*.Cu" "*.Mask")
			(remove_unused_layers no)
			(net "GND")
			(clearance -0.9779)
			(padstack
				(mode front_inner_back)
				(layer "Inner"
					(shape circle)
					(size 5.5372 5.5372)
					(clearance -0.6477)
				)
				(layer "B.Cu"
					(shape circle)
					(size 6.1976 6.1976)
					(clearance -0.9779)
				)
			)
		)
	)
	(footprint ""
		(layer "F.Cu")
		(at 185.799222 -23.113492)
		(property "Reference" "PR4000"
			(at 0 0 0)
			(layer "F.SilkS")
			(hide yes)
			(effects
				(font
					(size 1.27 1.27)
				)
			)
		)
		(property "Value" ""
			(at 0 0 0)
			(layer "F.Fab")
			(effects
				(font
					(size 1.27 1.27)
				)
			)
		)
		(duplicate_pad_numbers_are_jumpers no)
		(fp_line
			(start -0.7874 -0.4064)
			(end 0.7874 -0.4064)
			(stroke
				(width 0.1524)
				(type default)
			)
			(layer "F.SilkS")
		)
		(fp_line
			(start -0.7874 0.4064)
			(end -0.7874 -0.4064)
			(stroke
				(width 0.1524)
				(type default)
			)
			(layer "F.SilkS")
		)
		(fp_line
			(start 0.7874 -0.4064)
			(end 0.7874 0.4064)
			(stroke
				(width 0.1524)
				(type default)
			)
			(layer "F.SilkS")
		)
		(fp_line
			(start 0.7874 0.4064)
			(end -0.7874 0.4064)
			(stroke
				(width 0.1524)
				(type default)
			)
			(layer "F.SilkS")
		)
		(fp_line
			(start -0.67945 -0.305054)
			(end -0.12065 -0.305054)
			(stroke
				(width 0.1)
				(type default)
			)
			(layer "F.Fab")
		)
		(fp_line
			(start -0.67945 0.3048)
			(end -0.67945 -0.305054)
			(stroke
				(width 0.1)
				(type default)
			)
			(layer "F.Fab")
		)
		(fp_line
			(start -0.12065 -0.305054)
			(end -0.12065 -0.2794)
			(stroke
				(width 0.1)
				(type default)
			)
			(layer "F.Fab")
		)
		(fp_line
			(start -0.12065 -0.2794)
			(end 0.12065 -0.2794)
			(stroke
				(width 0.1)
				(type default)
			)
			(layer "F.Fab")
		)
		(fp_line
			(start -0.12065 0.2794)
			(end -0.12065 0.3048)
			(stroke
				(width 0.1)
				(type default)
			)
			(layer "F.Fab")
		)
		(fp_line
			(start -0.12065 0.3048)
			(end -0.67945 0.3048)
			(stroke
				(width 0.1)
				(type default)
			)
			(layer "F.Fab")
		)
		(fp_line
			(start 0.120396 0.2794)
			(end -0.12065 0.2794)
			(stroke
				(width 0.1)
				(type default)
			)
			(layer "F.Fab")
		)
		(fp_line
			(start 0.120396 0.3048)
			(end 0.120396 0.2794)
			(stroke
				(width 0.1)
				(type default)
			)
			(layer "F.Fab")
		)
		(fp_line
			(start 0.12065 -0.3048)
			(end 0.67945 -0.3048)
			(stroke
				(width 0.1)
				(type default)
			)
			(layer "F.Fab")
		)
		(fp_line
			(start 0.12065 -0.2794)
			(end 0.12065 -0.3048)
			(stroke
				(width 0.1)
				(type default)
			)
			(layer "F.Fab")
		)
		(fp_line
			(start 0.67945 -0.3048)
			(end 0.67945 0.3048)
			(stroke
				(width 0.1)
				(type default)
			)
			(layer "F.Fab")
		)
		(fp_line
			(start 0.67945 0.3048)
			(end 0.120396 0.3048)
			(stroke
				(width 0.1)
				(type default)
			)
			(layer "F.Fab")
		)
		(pad "1" smd circle
			(at -0.40005 0)
			(size 0 0)
			(layers "F.Cu" "F.Mask" "F.Paste")
			(net "P12V_AUX")
		)
		(pad "2" smd circle
			(at 0.40005 0)
			(size 0 0)
			(layers "F.Cu" "F.Mask" "F.Paste")
			(net "P12V_SCM_UV")
		)
	)
	(footprint ""
		(layer "F.Cu")
		(at 422.180766 -404.0124 -90)
		(property "Reference" "R1081"
			(at 0 0 270)
			(layer "F.SilkS")
			(hide yes)
			(effects
				(font
					(size 1.27 1.27)
				)
			)
		)
		(property "Value" ""
			(at 0 0 270)
			(layer "F.Fab")
			(effects
				(font
					(size 1.27 1.27)
				)
			)
		)
		(duplicate_pad_numbers_are_jumpers no)
		(fp_line
			(start -0.32512 0.175006)
			(end -0.32512 -0.175006)
			(stroke
				(width 0.1)
				(type default)
			)
			(layer "F.Fab")
		)
		(fp_line
			(start 0.32512 0.175006)
			(end -0.32512 0.175006)
			(stroke
				(width 0.1)
				(type default)
			)
			(layer "F.Fab")
		)
		(fp_line
			(start -0.32512 -0.175006)
			(end 0.32512 -0.175006)
			(stroke
				(width 0.1)
				(type default)
			)
			(layer "F.Fab")
		)
		(fp_line
			(start 0.32512 -0.175006)
			(end 0.32512 0.175006)
			(stroke
				(width 0.1)
				(type default)
			)
			(layer "F.Fab")
		)
		(pad "1" smd rect
			(at -0.2667 0 270)
			(size 0.3048 0.381)
			(layers "F.Cu" "F.Mask" "F.Paste")
			(net "P1V8_CPU0_RT_1D")
		)
		(pad "2" smd rect
			(at 0.2667 0 90)
			(size 0.3048 0.381)
			(layers "F.Cu" "F.Mask" "F.Paste")
			(net "RT_CPU0_P2_VQPS")
		)
	)
)
